(kicad_pcb
	(version 20260206)
	(generator "pcbnew")
	(generator_version "10.0")
	(general
		(thickness 1.21888)
		(legacy_teardrops no)
	)
	(paper "A4")
	(title_block
		(title "timecard-v8 — TimeCard-DC-V8_EXP.PcbDoc")
		(comment 1 "Time Appliance Project (Time Card) / footprints 251-263 of 288")
	)
	(layers
		(0 "F.Cu" signal "TOP")
		(4 "In1.Cu" signal "SGND")
		(6 "In2.Cu" signal "IN1")
		(8 "In3.Cu" signal "IN2")
		(10 "In4.Cu" signal "SGND1")
		(2 "B.Cu" signal "BOTTOM")
		(9 "F.Adhes" user "F.Adhesive")
		(11 "B.Adhes" user "B.Adhesive")
		(13 "F.Paste" user "Top Paste")
		(15 "B.Paste" user "Bottom Paste")
		(5 "F.SilkS" user "Top Overlay")
		(7 "B.SilkS" user "Bottom Overlay")
		(1 "F.Mask" user "Top Solder")
		(3 "B.Mask" user "Bottom Solder")
		(17 "Dwgs.User" user "User.Drawings")
		(19 "Cmts.User" user "User.Comments")
		(21 "Eco1.User" user "User.Eco1")
		(23 "Eco2.User" user "User.Eco2")
		(25 "Edge.Cuts" user)
		(27 "Margin" user)
		(31 "F.CrtYd" user "Top Courtyard")
		(29 "B.CrtYd" user "Bottom Courtyard")
		(35 "F.Fab" user "Top Component Center")
		(33 "B.Fab" user "Bottom Component Center")
	)
	(footprint "Vault:RESC1005X40X25LL10T10"
		(layer "F.Cu")
		(at 214.1261 113.5162 90)
		(property "Reference" "R9"
			(at -2.427 -0.395345 270)
			(unlocked yes)
			(layer "F.SilkS")
			(effects
				(font
					(size 0.762 0.762)
					(thickness 0.2286)
				)
				(justify left bottom)
			)
		)
		(property "Value" "1.21_1%_0402"
			(at -10.660245 10.4651 0)
			(unlocked yes)
			(layer "F.SilkS")
			(hide yes)
			(effects
				(font
					(size 0.762 0.762)
					(thickness 0.2286)
				)
				(justify left bottom)
			)
		)
		(sheetname "POWER")
		(sheetfile "POWER.kicad_sch")
		(duplicate_pad_numbers_are_jumpers no)
		(pad "1" smd rect
			(at -0.375 0 180)
			(size 0.5 0.55)
			(layers "F.Cu" "F.Mask" "F.Paste")
			(net "NetC7_1")
		)
		(pad "2" smd rect
			(at 0.375 0 180)
			(size 0.5 0.55)
			(layers "F.Cu" "F.Mask" "F.Paste")
			(net "NetL1_1")
		)
	)
	(footprint "Vault:RESC1608X55X30NL15T15"
		(layer "F.Cu")
		(at 84.1261 112.1162 -90)
		(property "Reference" "R29"
			(at 4 -0.593345 90)
			(unlocked yes)
			(layer "F.SilkS")
			(effects
				(font
					(size 0.762 0.762)
					(thickness 0.2286)
				)
				(justify left bottom)
			)
		)
		(property "Value" "4.7K"
			(at 3.636645 0.4445 0)
			(unlocked yes)
			(layer "F.SilkS")
			(hide yes)
			(effects
				(font
					(size 0.762 0.762)
					(thickness 0.2286)
				)
				(justify left bottom)
			)
		)
		(sheetname "USER_IO")
		(sheetfile "USER_IO.kicad_sch")
		(duplicate_pad_numbers_are_jumpers no)
		(pad "1" smd rect
			(at -0.75 0)
			(size 0.95 0.95)
			(layers "F.Cu" "F.Mask" "F.Paste")
			(net "ANT2_IO_OUT")
		)
		(pad "2" smd rect
			(at 0.75 0)
			(size 0.95 0.95)
			(layers "F.Cu" "F.Mask" "F.Paste")
			(net "+3.3V")
		)
	)
	(footprint "Vault:RESC1608X55X30NL15T15"
		(layer "F.Cu")
		(at 73.3761 55.6162 90)
		(property "Reference" "R38"
			(at -5.7714 0.026921 90)
			(unlocked yes)
			(layer "F.SilkS")
			(effects
				(font
					(size 0.762 0.762)
					(thickness 0.2286)
				)
			)
		)
		(property "Value" "200 OHM"
			(at -2.935471 4.78626 0)
			(unlocked yes)
			(layer "F.SilkS")
			(hide yes)
			(effects
				(font
					(size 0.762 0.762)
					(thickness 0.2286)
				)
			)
		)
		(sheetname "USER_IO_STATUS")
		(sheetfile "USER_IO_STATUS.kicad_sch")
		(duplicate_pad_numbers_are_jumpers no)
		(pad "1" smd rect
			(at -0.675 0 180)
			(size 0.95 0.8)
			(layers "F.Cu" "F.Mask" "F.Paste")
			(net "LED3")
		)
		(pad "2" smd rect
			(at 0.675 0 180)
			(size 0.95 0.8)
			(layers "F.Cu" "F.Mask" "F.Paste")
			(net "NetD10_1")
		)
	)
	(footprint "Vault:RESC3116X65X50ML20T20"
		(layer "F.Cu")
		(at 155.9123 83.7162)
		(property "Reference" "R46"
			(at 3.9286 0.126931 0)
			(unlocked yes)
			(layer "F.SilkS")
			(effects
				(font
					(size 0.762 0.762)
					(thickness 0.2286)
				)
			)
		)
		(property "Value" "DNI_0_5%_1206"
			(at 7.27402 3.291071 0)
			(unlocked yes)
			(layer "F.SilkS")
			(hide yes)
			(effects
				(font
					(size 0.762 0.762)
					(thickness 0.2286)
				)
			)
		)
		(sheetname "MAC")
		(sheetfile "MAC.kicad_sch")
		(duplicate_pad_numbers_are_jumpers no)
		(fp_line
			(start -0.35 -0.85)
			(end 0.35 -0.85)
			(stroke
				(width 0.2)
				(type solid)
			)
			(layer "F.SilkS")
		)
		(fp_line
			(start -0.35 0.85)
			(end 0.35 0.85)
			(stroke
				(width 0.2)
				(type solid)
			)
			(layer "F.SilkS")
		)
		(pad "1" smd rect
			(at -1.475 0 90)
			(size 1.9 1.45)
			(layers "F.Cu" "F.Mask" "F.Paste")
			(net "MAC_VCC")
		)
		(pad "2" smd rect
			(at 1.475 0 90)
			(size 1.9 1.45)
			(layers "F.Cu" "F.Mask" "F.Paste")
			(net "+12V")
		)
	)
	(footprint "Vault:RESC1608X55X30NL15T15"
		(layer "F.Cu")
		(at 82.3761 112.1162 -90)
		(property "Reference" "R30"
			(at 4 -0.593345 90)
			(unlocked yes)
			(layer "F.SilkS")
			(effects
				(font
					(size 0.762 0.762)
					(thickness 0.2286)
				)
				(justify left bottom)
			)
		)
		(property "Value" "4.7K"
			(at 3.636645 0.4445 0)
			(unlocked yes)
			(layer "F.SilkS")
			(hide yes)
			(effects
				(font
					(size 0.762 0.762)
					(thickness 0.2286)
				)
				(justify left bottom)
			)
		)
		(sheetname "USER_IO")
		(sheetfile "USER_IO.kicad_sch")
		(duplicate_pad_numbers_are_jumpers no)
		(pad "1" smd rect
			(at -0.75 0)
			(size 0.95 0.95)
			(layers "F.Cu" "F.Mask" "F.Paste")
			(net "ANT2_IO_IN")
		)
		(pad "2" smd rect
			(at 0.75 0)
			(size 0.95 0.95)
			(layers "F.Cu" "F.Mask" "F.Paste")
			(net "+3.3V")
		)
	)
	(footprint "Vault:RESC0402(1005)_N"
		(layer "F.Cu")
		(at 207.3261 111.5162 -90)
		(property "Reference" "R5"
			(at 1.3 0.393345 270)
			(unlocked yes)
			(layer "F.SilkS")
			(effects
				(font
					(size 0.762 0.762)
					(thickness 0.2286)
				)
				(justify left bottom)
			)
		)
		(property "Value" "1.21_1%_0402"
			(at 32.959045 -0.6183 0)
			(unlocked yes)
			(layer "F.SilkS")
			(hide yes)
			(effects
				(font
					(size 0.762 0.762)
					(thickness 0.2286)
				)
				(justify left bottom)
			)
		)
		(sheetname "POWER")
		(sheetfile "POWER.kicad_sch")
		(duplicate_pad_numbers_are_jumpers no)
		(pad "1" smd rect
			(at -0.5 -0.00001)
			(size 0.65 0.55)
			(layers "F.Cu" "F.Mask" "F.Paste")
			(net "P5V_VDD")
		)
		(pad "2" smd rect
			(at 0.5 -0.00001)
			(size 0.65 0.55)
			(layers "F.Cu" "F.Mask" "F.Paste")
			(net "P5V_PVDD")
		)
	)
	(footprint "Vault:RESC1005X40X25NL05T05"
		(layer "F.Cu")
		(at 235.9261 65.6162 180)
		(property "Reference" "R42"
			(at 0.4714 0.973079 0)
			(unlocked yes)
			(layer "F.SilkS")
			(effects
				(font
					(size 0.762 0.762)
					(thickness 0.2286)
				)
			)
		)
		(property "Value" "27_1%_0402"
			(at -3.011631 6.10665 90)
			(unlocked yes)
			(layer "F.SilkS")
			(hide yes)
			(effects
				(font
					(size 0.762 0.762)
					(thickness 0.2286)
				)
			)
		)
		(sheetname "USBUart_DipSelects")
		(sheetfile "USBUart_DipSelects.kicad_sch")
		(duplicate_pad_numbers_are_jumpers no)
		(pad "1" smd rect
			(at -0.45 0 270)
			(size 0.55 0.55)
			(layers "F.Cu" "F.Mask" "F.Paste")
			(net "NetR42_1")
		)
		(pad "2" smd rect
			(at 0.45 0 270)
			(size 0.55 0.55)
			(layers "F.Cu" "F.Mask" "F.Paste")
			(net "FTDI_RX")
		)
	)
	(footprint "Vault:FP-ERJ2RK-IPC_A"
		(layer "F.Cu")
		(at 237.4261 135.3162 180)
		(property "Reference" "R77"
			(at -2.5286 -0.026921 0)
			(unlocked yes)
			(layer "F.SilkS")
			(effects
				(font
					(size 0.762 0.762)
					(thickness 0.2286)
				)
			)
		)
		(property "Value" "200_1%_0402"
			(at -2.935471 7.782475 90)
			(unlocked yes)
			(layer "F.SilkS")
			(hide yes)
			(effects
				(font
					(size 0.762 0.762)
					(thickness 0.2286)
				)
			)
		)
		(sheetname "POWER")
		(sheetfile "POWER.kicad_sch")
		(duplicate_pad_numbers_are_jumpers no)
		(fp_line
			(start 0.83624 0.73624)
			(end -0.83624 0.73624)
			(stroke
				(width 0.2)
				(type solid)
			)
			(layer "F.SilkS")
		)
		(fp_line
			(start 0.83624 -0.73624)
			(end -0.83624 -0.73624)
			(stroke
				(width 0.2)
				(type solid)
			)
			(layer "F.SilkS")
		)
		(fp_line
			(start 1.03624 0.53624)
			(end -1.03623 0.53624)
			(stroke
				(width 0.2)
				(type solid)
			)
			(layer "F.CrtYd")
		)
		(fp_line
			(start 1.03624 -0.53624)
			(end 1.03624 0.53624)
			(stroke
				(width 0.2)
				(type solid)
			)
			(layer "F.CrtYd")
		)
		(fp_line
			(start 1.03624 -0.53624)
			(end -1.03623 -0.53624)
			(stroke
				(width 0.2)
				(type solid)
			)
			(layer "F.CrtYd")
		)
		(fp_line
			(start -1.03623 -0.53624)
			(end -1.03623 0.53624)
			(stroke
				(width 0.2)
				(type solid)
			)
			(layer "F.CrtYd")
		)
		(fp_line
			(start 1.03624 0.53624)
			(end -1.03623 0.53624)
			(stroke
				(width 0.2)
				(type solid)
			)
			(layer "F.Fab")
		)
		(fp_line
			(start 1.03624 -0.53624)
			(end 1.03624 0.53624)
			(stroke
				(width 0.2)
				(type solid)
			)
			(layer "F.Fab")
		)
		(fp_line
			(start 1.03624 -0.53624)
			(end -1.03623 -0.53624)
			(stroke
				(width 0.2)
				(type solid)
			)
			(layer "F.Fab")
		)
		(fp_line
			(start 0.5 0)
			(end -0.5 0)
			(stroke
				(width 0.1)
				(type solid)
			)
			(layer "F.Fab")
		)
		(fp_line
			(start 0 -0.5)
			(end 0 0.5)
			(stroke
				(width 0.1)
				(type solid)
			)
			(layer "F.Fab")
		)
		(fp_line
			(start -1.03623 -0.53624)
			(end -1.03623 0.53624)
			(stroke
				(width 0.2)
				(type solid)
			)
			(layer "F.Fab")
		)
		(fp_text user "${REFERENCE}"
			(at -0.00001 0.10711 180)
			(unlocked yes)
			(layer "F.Fab")
			(effects
				(font
					(face "Arial")
					(size 0.63 0.63)
					(thickness 0.1)
				)
				(justify left bottom)
			)
		)
		(pad "1" smd rect
			(at -0.50215 0 180)
			(size 0.66818 0.67248)
			(layers "F.Cu" "F.Mask" "F.Paste")
			(net "GND")
			(solder_mask_margin 0)
			(solder_paste_margin 0)
		)
		(pad "2" smd rect
			(at 0.50215 0 180)
			(size 0.66818 0.67248)
			(layers "F.Cu" "F.Mask" "F.Paste")
			(net "NetD20_1")
			(solder_mask_margin 0)
			(solder_paste_margin 0)
		)
	)
	(footprint "Vault:FP-0603-L_1_6_0_2-W_0_8_0-MFG"
		(layer "F.Cu")
		(at 234.4261 107.8162 -90)
		(property "Reference" "C15"
			(at -3.1 -0.206655 270)
			(unlocked yes)
			(layer "F.SilkS")
			(effects
				(font
					(size 0.762 0.762)
					(thickness 0.2286)
				)
				(justify left bottom)
			)
		)
		(property "Value" "10uF_16V_0603"
			(at 0.993045 -12.1875 0)
			(unlocked yes)
			(layer "F.SilkS")
			(hide yes)
			(effects
				(font
					(size 0.762 0.762)
					(thickness 0.2286)
				)
				(justify left bottom)
			)
		)
		(sheetname "POWER")
		(sheetfile "POWER.kicad_sch")
		(duplicate_pad_numbers_are_jumpers no)
		(fp_line
			(start 0.9 0.825)
			(end -0.9 0.825)
			(stroke
				(width 0.2)
				(type solid)
			)
			(layer "F.SilkS")
		)
		(fp_line
			(start 0.9 -0.825)
			(end -0.9 -0.825)
			(stroke
				(width 0.2)
				(type solid)
			)
			(layer "F.SilkS")
		)
		(fp_line
			(start -1.15 0.6)
			(end -1.15 -0.6)
			(stroke
				(width 0.2)
				(type solid)
			)
			(layer "F.CrtYd")
		)
		(fp_line
			(start 1.15 0.6)
			(end -1.15 0.6)
			(stroke
				(width 0.2)
				(type solid)
			)
			(layer "F.CrtYd")
		)
		(fp_line
			(start 1.15 0.6)
			(end 1.15 -0.6)
			(stroke
				(width 0.2)
				(type solid)
			)
			(layer "F.CrtYd")
		)
		(fp_line
			(start 1.15 -0.6)
			(end -1.15 -0.6)
			(stroke
				(width 0.2)
				(type solid)
			)
			(layer "F.CrtYd")
		)
		(fp_line
			(start -1.15 0.6)
			(end -1.15 -0.6)
			(stroke
				(width 0.2)
				(type solid)
			)
			(layer "F.Fab")
		)
		(fp_line
			(start 1.15 0.6)
			(end -1.15 0.6)
			(stroke
				(width 0.2)
				(type solid)
			)
			(layer "F.Fab")
		)
		(fp_line
			(start 1.15 0.6)
			(end 1.15 -0.6)
			(stroke
				(width 0.2)
				(type solid)
			)
			(layer "F.Fab")
		)
		(fp_line
			(start 0 0.5)
			(end 0 -0.5)
			(stroke
				(width 0.1)
				(type solid)
			)
			(layer "F.Fab")
		)
		(fp_line
			(start 0.5 0)
			(end -0.5 0)
			(stroke
				(width 0.1)
				(type solid)
			)
			(layer "F.Fab")
		)
		(fp_line
			(start 1.15 -0.6)
			(end -1.15 -0.6)
			(stroke
				(width 0.2)
				(type solid)
			)
			(layer "F.Fab")
		)
		(fp_text user "${REFERENCE}"
			(at -0.00001 0.09602 270)
			(unlocked yes)
			(layer "F.Fab")
			(effects
				(font
					(face "Arial")
					(size 0.63 0.63)
					(thickness 0.1)
				)
				(justify left bottom)
			)
		)
		(pad "1" smd rect
			(at -0.7 0 270)
			(size 0.7 0.7)
			(layers "F.Cu" "F.Mask" "F.Paste")
			(net "+5.0V")
			(solder_mask_margin 0)
			(solder_paste_margin 0)
		)
		(pad "2" smd rect
			(at 0.7 0 270)
			(size 0.7 0.7)
			(layers "F.Cu" "F.Mask" "F.Paste")
			(net "GND")
			(solder_mask_margin 0)
			(solder_paste_margin 0)
		)
	)
	(footprint "Vault:RESC1005X40X25ML05T10"
		(layer "F.Cu")
		(at 211.3261 128.7162)
		(property "Reference" "R71"
			(at -0.171395 2.226931 0)
			(unlocked yes)
			(layer "F.SilkS")
			(effects
				(font
					(size 0.762 0.762)
					(thickness 0.2286)
				)
			)
		)
		(property "Value" "2.21_1%_0402"
			(at -2.884671 8.544305 270)
			(unlocked yes)
			(layer "F.SilkS")
			(hide yes)
			(effects
				(font
					(size 0.762 0.762)
					(thickness 0.2286)
				)
			)
		)
		(sheetname "POWER")
		(sheetfile "POWER.kicad_sch")
		(duplicate_pad_numbers_are_jumpers no)
		(pad "1" smd rect
			(at -0.475 0 90)
			(size 0.65 0.7)
			(layers "F.Cu" "F.Mask" "F.Paste")
			(net "NetC68_2")
		)
		(pad "2" smd rect
			(at 0.475 0 90)
			(size 0.65 0.7)
			(layers "F.Cu" "F.Mask" "F.Paste")
			(net "NetL2_1")
		)
	)
	(footprint "Resistors:RESC1608X50N"
		(layer "F.Cu")
		(at 91.9361 122.0786 180)
		(property "Reference" "R22"
			(at 1.06 0.906655 0)
			(unlocked yes)
			(layer "F.SilkS")
			(effects
				(font
					(size 0.762 0.762)
					(thickness 0.2286)
				)
				(justify left bottom)
			)
		)
		(property "Value" "ERJ-3EKF4701V"
			(at 0.4445 -3.636645 0)
			(unlocked yes)
			(layer "F.SilkS")
			(hide yes)
			(effects
				(font
					(size 0.762 0.762)
					(thickness 0.2286)
				)
				(justify left bottom)
			)
		)
		(sheetname "PCIe_JTAG")
		(sheetfile "PCIe_JTAG.kicad_sch")
		(duplicate_pad_numbers_are_jumpers no)
		(fp_line
			(start 0 -0.5)
			(end 0 0.5)
			(stroke
				(width 0.1524)
				(type solid)
			)
			(layer "F.SilkS")
		)
		(pad "1" smd rect
			(at -0.69 0 270)
			(size 1 0.72)
			(layers "F.Cu" "F.Mask" "F.Paste")
			(net "PCIE_PERST")
		)
		(pad "2" smd rect
			(at 0.69 0 270)
			(size 1 0.72)
			(layers "F.Cu" "F.Mask" "F.Paste")
			(net "+3.3V")
		)
	)
	(footprint "Vault:AMPH-901-143-6RFX_V"
		(layer "F.Cu")
		(at 60.9761 95.0786 180)
		(property "Reference" "AN1"
			(at -5.993345 2.7124 90)
			(unlocked yes)
			(layer "F.SilkS")
			(effects
				(font
					(size 0.762 0.762)
					(thickness 0.2286)
				)
				(justify left bottom)
			)
		)
		(property "Value" "RF2-49B-T-00-50-G-HDW"
			(at 4.6101 -12.120245 0)
			(unlocked yes)
			(layer "F.SilkS")
			(hide yes)
			(effects
				(font
					(size 0.762 0.762)
					(thickness 0.2286)
				)
				(justify left bottom)
			)
		)
		(sheetname "USER_IO")
		(sheetfile "USER_IO.kicad_sch")
		(duplicate_pad_numbers_are_jumpers no)
		(fp_line
			(start 3.5 -1.38)
			(end 3.5 1.38)
			(stroke
				(width 0.2)
				(type solid)
			)
			(layer "F.SilkS")
		)
		(fp_line
			(start 1.38 3.5)
			(end -1.38 3.5)
			(stroke
				(width 0.2)
				(type solid)
			)
			(layer "F.SilkS")
		)
		(fp_line
			(start 1.38 -3.5)
			(end -1.38 -3.5)
			(stroke
				(width 0.2)
				(type solid)
			)
			(layer "F.SilkS")
		)
		(fp_line
			(start -3.5 -1.38)
			(end -3.5 1.38)
			(stroke
				(width 0.2)
				(type solid)
			)
			(layer "F.SilkS")
		)
		(pad "1" thru_hole rect
			(at 0 0 180)
			(size 2 2)
			(drill 1.5)
			(layers "*.Cu" "*.Mask")
			(remove_unused_layers no)
			(net "NetAN1_1")
		)
		(pad "2" thru_hole circle
			(at -2.54 -2.54 180)
			(size 2.2 2.2)
			(drill 1.7)
			(layers "*.Cu" "*.Mask")
			(remove_unused_layers no)
			(net "GND")
			(thermal_bridge_angle 90)
		)
		(pad "3" thru_hole circle
			(at -2.54 2.54 180)
			(size 2.2 2.2)
			(drill 1.7)
			(layers "*.Cu" "*.Mask")
			(remove_unused_layers no)
			(net "GND")
			(thermal_bridge_angle 90)
		)
		(pad "4" thru_hole circle
			(at 2.54 2.54 180)
			(size 2.2 2.2)
			(drill 1.7)
			(layers "*.Cu" "*.Mask")
			(remove_unused_layers no)
			(net "GND")
			(thermal_bridge_angle 90)
		)
		(pad "5" thru_hole circle
			(at 2.54 -2.54 180)
			(size 2.2 2.2)
			(drill 1.7)
			(layers "*.Cu" "*.Mask")
			(remove_unused_layers no)
			(net "GND")
			(thermal_bridge_angle 90)
		)
	)
	(footprint "Vault:CAPC1608X87X45ML20T05"
		(layer "F.Cu")
		(at 123.3261 82.6162)
		(property "Reference" "C24"
			(at -1.1714 -1.673079 0)
			(unlocked yes)
			(layer "F.SilkS")
			(effects
				(font
					(size 0.762 0.762)
					(thickness 0.2286)
				)
			)
		)
		(property "Value" "0.1uF"
			(at 2.069025 2.630671 0)
			(unlocked yes)
			(layer "F.SilkS")
			(hide yes)
			(effects
				(font
					(size 0.762 0.762)
					(thickness 0.2286)
				)
			)
		)
		(sheetname "MAC")
		(sheetfile "MAC.kicad_sch")
		(duplicate_pad_numbers_are_jumpers no)
		(pad "1" smd rect
			(at -0.7 0 90)
			(size 1.1 1.05)
			(layers "F.Cu" "F.Mask" "F.Paste")
			(net "+3.3V")
		)
		(pad "2" smd rect
			(at 0.7 0 90)
			(size 1.1 1.05)
			(layers "F.Cu" "F.Mask" "F.Paste")
			(net "GND")
		)
	)
)
